# S9S_MB_2U (Grand Teton) — schematic netlist excerpt (pin names and nets, part order shuffled) for the footprints in the layout excerpt that follows; sources: Cadence DE-HDL packaged netlist, KiCad conversion of 03242023_DA0F0TMBIJ0_F0T_Motherboard_J_brd_V01_OCP.brd

J66  PICOPROBE_BXA  DELTA-L 4.0 EMPTY  pkg TRIANG_LAUNCH_3PXB  page 308
  \1_p\  = DELTA_L_85_5INCH_IN2_DP
  \2_n\  = DELTA_L_85_5INCH_IN2_DN
  \3_g\  = DELTA_L_GND_1

(kicad_pcb
	(version 20260206)
	(generator "pcbnew")
	(generator_version "10.0")
	(general
		(thickness 1.6)
		(legacy_teardrops no)
	)
	(paper "A4")
	(title_block
		(title "03242023_DA0F0TMBIJ0_F0T_Motherboard_J_brd_V01_OCP.brd")
		(comment 1 "Grand Teton / footprints 1708-1708 of 6105")
	)
	(layers
		(0 "F.Cu" signal "TOP")
		(4 "In1.Cu" signal "GND")
		(6 "In2.Cu" signal "IN1")
		(8 "In3.Cu" signal "GND1")
		(10 "In4.Cu" signal "IN2")
		(12 "In5.Cu" signal "GND2")
		(14 "In6.Cu" signal "IN3")
		(16 "In7.Cu" signal "GND3")
		(18 "In8.Cu" signal "VCC")
		(20 "In9.Cu" signal "VCC1")
		(22 "In10.Cu" signal "GND4")
		(24 "In11.Cu" signal "IN4")
		(26 "In12.Cu" signal "GND5")
		(28 "In13.Cu" signal "IN5")
		(30 "In14.Cu" signal "GND6")
		(32 "In15.Cu" signal "IN6")
		(34 "In16.Cu" signal "GND7")
		(2 "B.Cu" signal "BOTTOM")
		(9 "F.Adhes" user "F.Adhesive")
		(11 "B.Adhes" user "B.Adhesive")
		(13 "F.Paste" user "Package Geometry/Pastemask Top")
		(15 "B.Paste" user "Package Geometry/Pastemask Bottom")
		(5 "F.SilkS" user "Ref Des/Silkscreen Top")
		(7 "B.SilkS" user "Ref Des/Silkscreen Bottom")
		(1 "F.Mask" user "Board Geometry/Soldermask Top")
		(3 "B.Mask" user "Board Geometry/Soldermask Bottom")
		(17 "Dwgs.User" user "User.Drawings")
		(19 "Cmts.User" user "User.Comments")
		(21 "Eco1.User" user "User.Eco1")
		(23 "Eco2.User" user "User.Eco2")
		(25 "Edge.Cuts" user "Board Geometry/Outline")
		(27 "Margin" user)
		(31 "F.CrtYd" user "Package Geometry/Place Bound Top")
		(29 "B.CrtYd" user "Package Geometry/Place Bound Bottom")
		(35 "F.Fab" user "Ref Des/Assembly Top")
		(33 "B.Fab" user "Ref Des/Assembly Bottom")
	)
	(footprint ""
		(layer "F.Cu")
		(at 378.099574 5.463794 180)
		(property "Reference" "J66"
			(at -4.451096 -1.394206 90)
			(unlocked yes)
			(layer "F.SilkS")
			(effects
				(font
					(size 0.7874 0.5842)
					(thickness 0.1524)
				)
				(justify left)
			)
		)
		(property "Value" ""
			(at 0 0 180)
			(layer "F.Fab")
			(effects
				(font
					(size 1.27 1.27)
				)
			)
		)
		(duplicate_pad_numbers_are_jumpers no)
		(fp_line
			(start 1.2192 2.1082)
			(end -1.2192 2.1082)
			(stroke
				(width 0.1524)
				(type default)
			)
			(layer "F.SilkS")
		)
		(fp_line
			(start 1.2192 -2.1082)
			(end 1.2192 2.1082)
			(stroke
				(width 0.1524)
				(type default)
			)
			(layer "F.SilkS")
		)
		(fp_line
			(start -1.2192 2.1082)
			(end -1.2192 -2.1082)
			(stroke
				(width 0.1524)
				(type default)
			)
			(layer "F.SilkS")
		)
		(fp_line
			(start -1.2192 -2.1082)
			(end 1.2192 -2.1082)
			(stroke
				(width 0.1524)
				(type default)
			)
			(layer "F.SilkS")
		)
		(pad "" np_thru_hole circle
			(at -2.8829 -1.27 90)
			(size 1.0414 1.0414)
			(drill 1.0414)
			(layers "*.Cu" "*.Mask")
			(clearance 0.381)
			(thermal_gap 0.381)
		)
		(pad "" np_thru_hole circle
			(at -2.8829 1.27 90)
			(size 1.0414 1.0414)
			(drill 1.0414)
			(layers "*.Cu" "*.Mask")
			(clearance 0.381)
			(thermal_gap 0.381)
		)
		(pad "" np_thru_hole circle
			(at 3.4671 -1.27 90)
			(size 1.0414 1.0414)
			(drill 1.0414)
			(layers "*.Cu" "*.Mask")
			(clearance 0.381)
			(thermal_gap 0.381)
		)
		(pad "" np_thru_hole circle
			(at 3.4671 1.27 90)
			(size 1.0414 1.0414)
			(drill 1.0414)
			(layers "*.Cu" "*.Mask")
			(clearance 0.381)
			(thermal_gap 0.381)
		)
		(pad "1" smd rect
			(at 0.8255 -0.249936 90)
			(size 0.3048 0.508)
			(layers "F.Cu" "F.Mask" "F.Paste")
			(net "DELTA_L_85_5INCH_IN2_DP")
		)
		(pad "2" smd rect
			(at 0.8255 0.249936 90)
			(size 0.3048 0.508)
			(layers "F.Cu" "F.Mask" "F.Paste")
			(net "DELTA_L_85_5INCH_IN2_DN")
		)
		(pad "3" smd circle
			(at 0 0 180)
			(size 0 0)
			(layers "F.Cu" "F.Mask" "F.Paste")
			(net "DELTA_L_GND_1")
		)
		(zone
			(layer "F.Cu")
			(hatch none 0.5)
			(connect_pads
				(clearance 0)
			)
			(min_thickness 0.25)
			(keepout
				(tracks not_allowed)
				(vias allowed)
				(pads allowed)
				(copperpour not_allowed)
				(footprints allowed)
			)
			(placement
				(enabled no)
				(sheetname "")
			)
			(fill
				(thermal_gap 0.5)
				(thermal_bridge_width 0.5)
				(island_removal_mode 0)
			)
			(polygon
				(pts
					(xy 376.981974 6.012434) (xy 376.981974 5.91693) (xy 377.578874 5.91693) (xy 377.578874 5.51053)
					(xy 376.981974 5.51053) (xy 376.981974 5.417058) (xy 377.578874 5.417058) (xy 377.578874 5.010658)
					(xy 376.981974 5.010658) (xy 376.981974 4.915154) (xy 377.680474 4.915154) (xy 377.680474 6.012434)
				)
			)
		)
		(zone
			(layers "F.Cu" "B.Cu" "In1.Cu" "In2.Cu" "In3.Cu" "In4.Cu" "In5.Cu" "In6.Cu"
				"In7.Cu" "In8.Cu" "In9.Cu" "In10.Cu" "In11.Cu" "In12.Cu" "In13.Cu" "In14.Cu"
				"In15.Cu" "In16.Cu"
			)
			(hatch none 0.5)
			(connect_pads
				(clearance 0)
			)
			(min_thickness 0.25)
			(keepout
				(tracks not_allowed)
				(vias allowed)
				(pads allowed)
				(copperpour not_allowed)
				(footprints allowed)
			)
			(placement
				(enabled no)
				(sheetname "")
			)
			(fill
				(thermal_gap 0.5)
				(thermal_bridge_width 0.5)
				(island_removal_mode 0)
			)
			(polygon
				(pts
					(arc
						(start 375.559574 4.193794)
						(mid 373.705374 4.193794)
						(end 375.559574 4.193794)
					)
				)
			)
		)
		(zone
			(layers "F.Cu" "B.Cu" "In1.Cu" "In2.Cu" "In3.Cu" "In4.Cu" "In5.Cu" "In6.Cu"
				"In7.Cu" "In8.Cu" "In9.Cu" "In10.Cu" "In11.Cu" "In12.Cu" "In13.Cu" "In14.Cu"
				"In15.Cu" "In16.Cu"
			)
			(hatch none 0.5)
			(connect_pads
				(clearance 0)
			)
			(min_thickness 0.25)
			(keepout
				(tracks not_allowed)
				(vias allowed)
				(pads allowed)
				(copperpour not_allowed)
				(footprints allowed)
			)
			(placement
				(enabled no)
				(sheetname "")
			)
			(fill
				(thermal_gap 0.5)
				(thermal_bridge_width 0.5)
				(island_removal_mode 0)
			)
			(polygon
				(pts
					(arc
						(start 375.559574 6.733794)
						(mid 373.705374 6.733794)
						(end 375.559574 6.733794)
					)
				)
			)
		)
		(zone
			(layers "F.Cu" "B.Cu" "In1.Cu" "In2.Cu" "In3.Cu" "In4.Cu" "In5.Cu" "In6.Cu"
				"In7.Cu" "In8.Cu" "In9.Cu" "In10.Cu" "In11.Cu" "In12.Cu" "In13.Cu" "In14.Cu"
				"In15.Cu" "In16.Cu"
			)
			(hatch none 0.5)
			(connect_pads
				(clearance 0)
			)
			(min_thickness 0.25)
			(keepout
				(tracks not_allowed)
				(vias allowed)
				(pads allowed)
				(copperpour not_allowed)
				(footprints allowed)
			)
			(placement
				(enabled no)
				(sheetname "")
			)
			(fill
				(thermal_gap 0.5)
				(thermal_bridge_width 0.5)
				(island_removal_mode 0)
			)
			(polygon
				(pts
					(arc
						(start 381.909574 4.193794)
						(mid 380.055374 4.193794)
						(end 381.909574 4.193794)
					)
				)
			)
		)
		(zone
			(layers "F.Cu" "B.Cu" "In1.Cu" "In2.Cu" "In3.Cu" "In4.Cu" "In5.Cu" "In6.Cu"
				"In7.Cu" "In8.Cu" "In9.Cu" "In10.Cu" "In11.Cu" "In12.Cu" "In13.Cu" "In14.Cu"
				"In15.Cu" "In16.Cu"
			)
			(hatch none 0.5)
			(connect_pads
				(clearance 0)
			)
			(min_thickness 0.25)
			(keepout
				(tracks not_allowed)
				(vias allowed)
				(pads allowed)
				(copperpour not_allowed)
				(footprints allowed)
			)
			(placement
				(enabled no)
				(sheetname "")
			)
			(fill
				(thermal_gap 0.5)
				(thermal_bridge_width 0.5)
				(island_removal_mode 0)
			)
			(polygon
				(pts
					(arc
						(start 381.909574 6.733794)
						(mid 380.055374 6.733794)
						(end 381.909574 6.733794)
					)
				)
			)
		)
	)
)
